(kicad_pcb
	(version 20260206)
	(generator "pcbnew")
	(generator_version "10.0")
	(general
		(thickness 1.6)
		(legacy_teardrops no)
	)
	(paper "A4")
	(title_block
		(title "03242023_DA0F0TMBIJ0_F0T_Motherboard_J_brd_V01_OCP.brd")
		(comment 1 "Grand Teton / footprints 1756-1761 of 6105")
	)
	(layers
		(0 "F.Cu" signal "TOP")
		(4 "In1.Cu" signal "GND")
		(6 "In2.Cu" signal "IN1")
		(8 "In3.Cu" signal "GND1")
		(10 "In4.Cu" signal "IN2")
		(12 "In5.Cu" signal "GND2")
		(14 "In6.Cu" signal "IN3")
		(16 "In7.Cu" signal "GND3")
		(18 "In8.Cu" signal "VCC")
		(20 "In9.Cu" signal "VCC1")
		(22 "In10.Cu" signal "GND4")
		(24 "In11.Cu" signal "IN4")
		(26 "In12.Cu" signal "GND5")
		(28 "In13.Cu" signal "IN5")
		(30 "In14.Cu" signal "GND6")
		(32 "In15.Cu" signal "IN6")
		(34 "In16.Cu" signal "GND7")
		(2 "B.Cu" signal "BOTTOM")
		(9 "F.Adhes" user "F.Adhesive")
		(11 "B.Adhes" user "B.Adhesive")
		(13 "F.Paste" user "Package Geometry/Pastemask Top")
		(15 "B.Paste" user "Package Geometry/Pastemask Bottom")
		(5 "F.SilkS" user "Ref Des/Silkscreen Top")
		(7 "B.SilkS" user "Ref Des/Silkscreen Bottom")
		(1 "F.Mask" user "Board Geometry/Soldermask Top")
		(3 "B.Mask" user "Board Geometry/Soldermask Bottom")
		(17 "Dwgs.User" user "User.Drawings")
		(19 "Cmts.User" user "User.Comments")
		(21 "Eco1.User" user "User.Eco1")
		(23 "Eco2.User" user "User.Eco2")
		(25 "Edge.Cuts" user "Board Geometry/Outline")
		(27 "Margin" user)
		(31 "F.CrtYd" user "Package Geometry/Place Bound Top")
		(29 "B.CrtYd" user "Package Geometry/Place Bound Bottom")
		(35 "F.Fab" user "Ref Des/Assembly Top")
		(33 "B.Fab" user "Ref Des/Assembly Bottom")
	)
	(footprint ""
		(layer "F.Cu")
		(at 348.929198 -337.856068)
		(property "Reference" "PC297_P0_1"
			(at 0 0 0)
			(layer "F.SilkS")
			(hide yes)
			(effects
				(font
					(size 1.27 1.27)
				)
			)
		)
		(property "Value" ""
			(at 0 0 0)
			(layer "F.Fab")
			(effects
				(font
					(size 1.27 1.27)
				)
			)
		)
		(duplicate_pad_numbers_are_jumpers no)
		(fp_line
			(start -0.7874 -0.4064)
			(end 0.7874 -0.4064)
			(stroke
				(width 0.1524)
				(type default)
			)
			(layer "F.SilkS")
		)
		(fp_line
			(start -0.7874 0.4064)
			(end -0.7874 -0.4064)
			(stroke
				(width 0.1524)
				(type default)
			)
			(layer "F.SilkS")
		)
		(fp_line
			(start 0.7874 -0.4064)
			(end 0.7874 0.4064)
			(stroke
				(width 0.1524)
				(type default)
			)
			(layer "F.SilkS")
		)
		(fp_line
			(start 0.7874 0.4064)
			(end -0.7874 0.4064)
			(stroke
				(width 0.1524)
				(type default)
			)
			(layer "F.SilkS")
		)
		(fp_line
			(start -0.67945 -0.305054)
			(end -0.12065 -0.305054)
			(stroke
				(width 0.1)
				(type default)
			)
			(layer "F.Fab")
		)
		(fp_line
			(start -0.67945 0.3048)
			(end -0.67945 -0.305054)
			(stroke
				(width 0.1)
				(type default)
			)
			(layer "F.Fab")
		)
		(fp_line
			(start -0.12065 -0.305054)
			(end -0.12065 -0.2794)
			(stroke
				(width 0.1)
				(type default)
			)
			(layer "F.Fab")
		)
		(fp_line
			(start -0.12065 -0.2794)
			(end 0.12065 -0.2794)
			(stroke
				(width 0.1)
				(type default)
			)
			(layer "F.Fab")
		)
		(fp_line
			(start -0.12065 0.2794)
			(end -0.12065 0.3048)
			(stroke
				(width 0.1)
				(type default)
			)
			(layer "F.Fab")
		)
		(fp_line
			(start -0.12065 0.3048)
			(end -0.67945 0.3048)
			(stroke
				(width 0.1)
				(type default)
			)
			(layer "F.Fab")
		)
		(fp_line
			(start 0.120396 0.2794)
			(end -0.12065 0.2794)
			(stroke
				(width 0.1)
				(type default)
			)
			(layer "F.Fab")
		)
		(fp_line
			(start 0.120396 0.3048)
			(end 0.120396 0.2794)
			(stroke
				(width 0.1)
				(type default)
			)
			(layer "F.Fab")
		)
		(fp_line
			(start 0.12065 -0.3048)
			(end 0.67945 -0.3048)
			(stroke
				(width 0.1)
				(type default)
			)
			(layer "F.Fab")
		)
		(fp_line
			(start 0.12065 -0.2794)
			(end 0.12065 -0.3048)
			(stroke
				(width 0.1)
				(type default)
			)
			(layer "F.Fab")
		)
		(fp_line
			(start 0.67945 -0.3048)
			(end 0.67945 0.3048)
			(stroke
				(width 0.1)
				(type default)
			)
			(layer "F.Fab")
		)
		(fp_line
			(start 0.67945 0.3048)
			(end 0.120396 0.3048)
			(stroke
				(width 0.1)
				(type default)
			)
			(layer "F.Fab")
		)
		(pad "1" smd circle
			(at -0.40005 0)
			(size 0 0)
			(layers "F.Cu" "F.Mask" "F.Paste")
			(net "SW_P12V_PVCCIN_CPU0_FLT")
		)
		(pad "2" smd circle
			(at 0.40005 0)
			(size 0 0)
			(layers "F.Cu" "F.Mask" "F.Paste")
			(net "GND")
		)
	)
	(footprint ""
		(layer "F.Cu")
		(at 224.20961 -46.524926)
		(property "Reference" "R1673"
			(at 0 0 0)
			(layer "F.SilkS")
			(hide yes)
			(effects
				(font
					(size 1.27 1.27)
				)
			)
		)
		(property "Value" ""
			(at 0 0 0)
			(layer "F.Fab")
			(effects
				(font
					(size 1.27 1.27)
				)
			)
		)
		(duplicate_pad_numbers_are_jumpers no)
		(fp_line
			(start -0.7874 -0.4064)
			(end 0.7874 -0.4064)
			(stroke
				(width 0.1524)
				(type default)
			)
			(layer "F.SilkS")
		)
		(fp_line
			(start -0.7874 0.4064)
			(end -0.7874 -0.4064)
			(stroke
				(width 0.1524)
				(type default)
			)
			(layer "F.SilkS")
		)
		(fp_line
			(start 0.7874 -0.4064)
			(end 0.7874 0.4064)
			(stroke
				(width 0.1524)
				(type default)
			)
			(layer "F.SilkS")
		)
		(fp_line
			(start 0.7874 0.4064)
			(end -0.7874 0.4064)
			(stroke
				(width 0.1524)
				(type default)
			)
			(layer "F.SilkS")
		)
		(fp_line
			(start -0.67945 -0.305054)
			(end -0.12065 -0.305054)
			(stroke
				(width 0.1)
				(type default)
			)
			(layer "F.Fab")
		)
		(fp_line
			(start -0.67945 0.3048)
			(end -0.67945 -0.305054)
			(stroke
				(width 0.1)
				(type default)
			)
			(layer "F.Fab")
		)
		(fp_line
			(start -0.12065 -0.305054)
			(end -0.12065 -0.2794)
			(stroke
				(width 0.1)
				(type default)
			)
			(layer "F.Fab")
		)
		(fp_line
			(start -0.12065 -0.2794)
			(end 0.12065 -0.2794)
			(stroke
				(width 0.1)
				(type default)
			)
			(layer "F.Fab")
		)
		(fp_line
			(start -0.12065 0.2794)
			(end -0.12065 0.3048)
			(stroke
				(width 0.1)
				(type default)
			)
			(layer "F.Fab")
		)
		(fp_line
			(start -0.12065 0.3048)
			(end -0.67945 0.3048)
			(stroke
				(width 0.1)
				(type default)
			)
			(layer "F.Fab")
		)
		(fp_line
			(start 0.120396 0.2794)
			(end -0.12065 0.2794)
			(stroke
				(width 0.1)
				(type default)
			)
			(layer "F.Fab")
		)
		(fp_line
			(start 0.120396 0.3048)
			(end 0.120396 0.2794)
			(stroke
				(width 0.1)
				(type default)
			)
			(layer "F.Fab")
		)
		(fp_line
			(start 0.12065 -0.3048)
			(end 0.67945 -0.3048)
			(stroke
				(width 0.1)
				(type default)
			)
			(layer "F.Fab")
		)
		(fp_line
			(start 0.12065 -0.2794)
			(end 0.12065 -0.3048)
			(stroke
				(width 0.1)
				(type default)
			)
			(layer "F.Fab")
		)
		(fp_line
			(start 0.67945 -0.3048)
			(end 0.67945 0.3048)
			(stroke
				(width 0.1)
				(type default)
			)
			(layer "F.Fab")
		)
		(fp_line
			(start 0.67945 0.3048)
			(end 0.120396 0.3048)
			(stroke
				(width 0.1)
				(type default)
			)
			(layer "F.Fab")
		)
		(pad "1" smd circle
			(at -0.40005 0)
			(size 0 0)
			(layers "F.Cu" "F.Mask" "F.Paste")
			(net "P3V3_E1S_0")
		)
		(pad "2" smd circle
			(at 0.40005 0)
			(size 0 0)
			(layers "F.Cu" "F.Mask" "F.Paste")
			(net "RST_SMB_E1S_0_N")
		)
	)
	(footprint ""
		(layer "F.Cu")
		(at 22.91842 -428.401988)
		(property "Reference" "R4622"
			(at 0 0 0)
			(layer "F.SilkS")
			(hide yes)
			(effects
				(font
					(size 1.27 1.27)
				)
			)
		)
		(property "Value" ""
			(at 0 0 0)
			(layer "F.Fab")
			(effects
				(font
					(size 1.27 1.27)
				)
			)
		)
		(duplicate_pad_numbers_are_jumpers no)
		(fp_line
			(start -0.7874 -0.4064)
			(end 0.7874 -0.4064)
			(stroke
				(width 0.1524)
				(type default)
			)
			(layer "F.SilkS")
		)
		(fp_line
			(start -0.7874 0.4064)
			(end -0.7874 -0.4064)
			(stroke
				(width 0.1524)
				(type default)
			)
			(layer "F.SilkS")
		)
		(fp_line
			(start 0.7874 -0.4064)
			(end 0.7874 0.4064)
			(stroke
				(width 0.1524)
				(type default)
			)
			(layer "F.SilkS")
		)
		(fp_line
			(start 0.7874 0.4064)
			(end -0.7874 0.4064)
			(stroke
				(width 0.1524)
				(type default)
			)
			(layer "F.SilkS")
		)
		(fp_line
			(start -0.67945 -0.305054)
			(end -0.12065 -0.305054)
			(stroke
				(width 0.1)
				(type default)
			)
			(layer "F.Fab")
		)
		(fp_line
			(start -0.67945 0.3048)
			(end -0.67945 -0.305054)
			(stroke
				(width 0.1)
				(type default)
			)
			(layer "F.Fab")
		)
		(fp_line
			(start -0.12065 -0.305054)
			(end -0.12065 -0.2794)
			(stroke
				(width 0.1)
				(type default)
			)
			(layer "F.Fab")
		)
		(fp_line
			(start -0.12065 -0.2794)
			(end 0.12065 -0.2794)
			(stroke
				(width 0.1)
				(type default)
			)
			(layer "F.Fab")
		)
		(fp_line
			(start -0.12065 0.2794)
			(end -0.12065 0.3048)
			(stroke
				(width 0.1)
				(type default)
			)
			(layer "F.Fab")
		)
		(fp_line
			(start -0.12065 0.3048)
			(end -0.67945 0.3048)
			(stroke
				(width 0.1)
				(type default)
			)
			(layer "F.Fab")
		)
		(fp_line
			(start 0.120396 0.2794)
			(end -0.12065 0.2794)
			(stroke
				(width 0.1)
				(type default)
			)
			(layer "F.Fab")
		)
		(fp_line
			(start 0.120396 0.3048)
			(end 0.120396 0.2794)
			(stroke
				(width 0.1)
				(type default)
			)
			(layer "F.Fab")
		)
		(fp_line
			(start 0.12065 -0.3048)
			(end 0.67945 -0.3048)
			(stroke
				(width 0.1)
				(type default)
			)
			(layer "F.Fab")
		)
		(fp_line
			(start 0.12065 -0.2794)
			(end 0.12065 -0.3048)
			(stroke
				(width 0.1)
				(type default)
			)
			(layer "F.Fab")
		)
		(fp_line
			(start 0.67945 -0.3048)
			(end 0.67945 0.3048)
			(stroke
				(width 0.1)
				(type default)
			)
			(layer "F.Fab")
		)
		(fp_line
			(start 0.67945 0.3048)
			(end 0.120396 0.3048)
			(stroke
				(width 0.1)
				(type default)
			)
			(layer "F.Fab")
		)
		(pad "1" smd circle
			(at -0.40005 0)
			(size 0 0)
			(layers "F.Cu" "F.Mask" "F.Paste")
			(net "RST_PERST_SWB_N")
		)
		(pad "2" smd circle
			(at 0.40005 0)
			(size 0 0)
			(layers "F.Cu" "F.Mask" "F.Paste")
			(net "GND")
		)
	)
	(footprint ""
		(layer "F.Cu")
		(at 303.9872 -23.6728)
		(property "Reference" "R4790"
			(at 0 0 0)
			(layer "F.SilkS")
			(hide yes)
			(effects
				(font
					(size 1.27 1.27)
				)
			)
		)
		(property "Value" ""
			(at 0 0 0)
			(layer "F.Fab")
			(effects
				(font
					(size 1.27 1.27)
				)
			)
		)
		(duplicate_pad_numbers_are_jumpers no)
		(fp_line
			(start -0.7874 -0.4064)
			(end 0.7874 -0.4064)
			(stroke
				(width 0.1524)
				(type default)
			)
			(layer "F.SilkS")
		)
		(fp_line
			(start -0.7874 0.4064)
			(end -0.7874 -0.4064)
			(stroke
				(width 0.1524)
				(type default)
			)
			(layer "F.SilkS")
		)
		(fp_line
			(start 0.7874 -0.4064)
			(end 0.7874 0.4064)
			(stroke
				(width 0.1524)
				(type default)
			)
			(layer "F.SilkS")
		)
		(fp_line
			(start 0.7874 0.4064)
			(end -0.7874 0.4064)
			(stroke
				(width 0.1524)
				(type default)
			)
			(layer "F.SilkS")
		)
		(fp_line
			(start -0.67945 -0.305054)
			(end -0.12065 -0.305054)
			(stroke
				(width 0.1)
				(type default)
			)
			(layer "F.Fab")
		)
		(fp_line
			(start -0.67945 0.3048)
			(end -0.67945 -0.305054)
			(stroke
				(width 0.1)
				(type default)
			)
			(layer "F.Fab")
		)
		(fp_line
			(start -0.12065 -0.305054)
			(end -0.12065 -0.2794)
			(stroke
				(width 0.1)
				(type default)
			)
			(layer "F.Fab")
		)
		(fp_line
			(start -0.12065 -0.2794)
			(end 0.12065 -0.2794)
			(stroke
				(width 0.1)
				(type default)
			)
			(layer "F.Fab")
		)
		(fp_line
			(start -0.12065 0.2794)
			(end -0.12065 0.3048)
			(stroke
				(width 0.1)
				(type default)
			)
			(layer "F.Fab")
		)
		(fp_line
			(start -0.12065 0.3048)
			(end -0.67945 0.3048)
			(stroke
				(width 0.1)
				(type default)
			)
			(layer "F.Fab")
		)
		(fp_line
			(start 0.120396 0.2794)
			(end -0.12065 0.2794)
			(stroke
				(width 0.1)
				(type default)
			)
			(layer "F.Fab")
		)
		(fp_line
			(start 0.120396 0.3048)
			(end 0.120396 0.2794)
			(stroke
				(width 0.1)
				(type default)
			)
			(layer "F.Fab")
		)
		(fp_line
			(start 0.12065 -0.3048)
			(end 0.67945 -0.3048)
			(stroke
				(width 0.1)
				(type default)
			)
			(layer "F.Fab")
		)
		(fp_line
			(start 0.12065 -0.2794)
			(end 0.12065 -0.3048)
			(stroke
				(width 0.1)
				(type default)
			)
			(layer "F.Fab")
		)
		(fp_line
			(start 0.67945 -0.3048)
			(end 0.67945 0.3048)
			(stroke
				(width 0.1)
				(type default)
			)
			(layer "F.Fab")
		)
		(fp_line
			(start 0.67945 0.3048)
			(end 0.120396 0.3048)
			(stroke
				(width 0.1)
				(type default)
			)
			(layer "F.Fab")
		)
		(pad "1" smd circle
			(at -0.40005 0)
			(size 0 0)
			(layers "F.Cu" "F.Mask" "F.Paste")
			(net "P12V_AUX")
		)
		(pad "2" smd circle
			(at 0.40005 0)
			(size 0 0)
			(layers "F.Cu" "F.Mask" "F.Paste")
			(net "PWRGD_DSW_PWROK_TRIGGER")
		)
	)
	(footprint ""
		(layer "F.Cu")
		(at 341.362792 -336.192368 90)
		(property "Reference" "PC293"
			(at 0 0 90)
			(layer "F.SilkS")
			(hide yes)
			(effects
				(font
					(size 1.27 1.27)
				)
			)
		)
		(property "Value" ""
			(at 0 0 90)
			(layer "F.Fab")
			(effects
				(font
					(size 1.27 1.27)
				)
			)
		)
		(duplicate_pad_numbers_are_jumpers no)
		(fp_line
			(start 0.7874 -0.4064)
			(end 0.7874 0.4064)
			(stroke
				(width 0.1524)
				(type default)
			)
			(layer "F.SilkS")
		)
		(fp_line
			(start -0.7874 -0.4064)
			(end 0.7874 -0.4064)
			(stroke
				(width 0.1524)
				(type default)
			)
			(layer "F.SilkS")
		)
		(fp_line
			(start 0.7874 0.4064)
			(end -0.7874 0.4064)
			(stroke
				(width 0.1524)
				(type default)
			)
			(layer "F.SilkS")
		)
		(fp_line
			(start -0.7874 0.4064)
			(end -0.7874 -0.4064)
			(stroke
				(width 0.1524)
				(type default)
			)
			(layer "F.SilkS")
		)
		(fp_line
			(start -0.12065 -0.305054)
			(end -0.12065 -0.2794)
			(stroke
				(width 0.1)
				(type default)
			)
			(layer "F.Fab")
		)
		(fp_line
			(start -0.67945 -0.305054)
			(end -0.12065 -0.305054)
			(stroke
				(width 0.1)
				(type default)
			)
			(layer "F.Fab")
		)
		(fp_line
			(start 0.67945 -0.3048)
			(end 0.67945 0.3048)
			(stroke
				(width 0.1)
				(type default)
			)
			(layer "F.Fab")
		)
		(fp_line
			(start 0.12065 -0.3048)
			(end 0.67945 -0.3048)
			(stroke
				(width 0.1)
				(type default)
			)
			(layer "F.Fab")
		)
		(fp_line
			(start 0.12065 -0.2794)
			(end 0.12065 -0.3048)
			(stroke
				(width 0.1)
				(type default)
			)
			(layer "F.Fab")
		)
		(fp_line
			(start -0.12065 -0.2794)
			(end 0.12065 -0.2794)
			(stroke
				(width 0.1)
				(type default)
			)
			(layer "F.Fab")
		)
		(fp_line
			(start 0.120396 0.2794)
			(end -0.12065 0.2794)
			(stroke
				(width 0.1)
				(type default)
			)
			(layer "F.Fab")
		)
		(fp_line
			(start -0.12065 0.2794)
			(end -0.12065 0.3048)
			(stroke
				(width 0.1)
				(type default)
			)
			(layer "F.Fab")
		)
		(fp_line
			(start 0.67945 0.3048)
			(end 0.120396 0.3048)
			(stroke
				(width 0.1)
				(type default)
			)
			(layer "F.Fab")
		)
		(fp_line
			(start 0.120396 0.3048)
			(end 0.120396 0.2794)
			(stroke
				(width 0.1)
				(type default)
			)
			(layer "F.Fab")
		)
		(fp_line
			(start -0.12065 0.3048)
			(end -0.67945 0.3048)
			(stroke
				(width 0.1)
				(type default)
			)
			(layer "F.Fab")
		)
		(fp_line
			(start -0.67945 0.3048)
			(end -0.67945 -0.305054)
			(stroke
				(width 0.1)
				(type default)
			)
			(layer "F.Fab")
		)
		(pad "1" smd circle
			(at -0.40005 0 90)
			(size 0 0)
			(layers "F.Cu" "F.Mask" "F.Paste")
			(net "PVCCIN_CPU0_VDD1")
		)
		(pad "2" smd circle
			(at 0.40005 0 90)
			(size 0 0)
			(layers "F.Cu" "F.Mask" "F.Paste")
			(net "GND")
		)
	)
	(footprint ""
		(layer "F.Cu")
		(at 309.55488 -49.494948 180)
		(property "Reference" "R1257"
			(at 0 0 180)
			(layer "F.SilkS")
			(hide yes)
			(effects
				(font
					(size 1.27 1.27)
				)
			)
		)
		(property "Value" ""
			(at 0 0 180)
			(layer "F.Fab")
			(effects
				(font
					(size 1.27 1.27)
				)
			)
		)
		(duplicate_pad_numbers_are_jumpers no)
		(fp_line
			(start 0.7874 0.4064)
			(end -0.7874 0.4064)
			(stroke
				(width 0.1524)
				(type default)
			)
			(layer "F.SilkS")
		)
		(fp_line
			(start 0.7874 -0.4064)
			(end 0.7874 0.4064)
			(stroke
				(width 0.1524)
				(type default)
			)
			(layer "F.SilkS")
		)
		(fp_line
			(start -0.7874 0.4064)
			(end -0.7874 -0.4064)
			(stroke
				(width 0.1524)
				(type default)
			)
			(layer "F.SilkS")
		)
		(fp_line
			(start -0.7874 -0.4064)
			(end 0.7874 -0.4064)
			(stroke
				(width 0.1524)
				(type default)
			)
			(layer "F.SilkS")
		)
		(fp_line
			(start 0.67945 0.3048)
			(end 0.120396 0.3048)
			(stroke
				(width 0.1)
				(type default)
			)
			(layer "F.Fab")
		)
		(fp_line
			(start 0.67945 -0.3048)
			(end 0.67945 0.3048)
			(stroke
				(width 0.1)
				(type default)
			)
			(layer "F.Fab")
		)
		(fp_line
			(start 0.12065 -0.2794)
			(end 0.12065 -0.3048)
			(stroke
				(width 0.1)
				(type default)
			)
			(layer "F.Fab")
		)
		(fp_line
			(start 0.12065 -0.3048)
			(end 0.67945 -0.3048)
			(stroke
				(width 0.1)
				(type default)
			)
			(layer "F.Fab")
		)
		(fp_line
			(start 0.120396 0.3048)
			(end 0.120396 0.2794)
			(stroke
				(width 0.1)
				(type default)
			)
			(layer "F.Fab")
		)
		(fp_line
			(start 0.120396 0.2794)
			(end -0.12065 0.2794)
			(stroke
				(width 0.1)
				(type default)
			)
			(layer "F.Fab")
		)
		(fp_line
			(start -0.12065 0.3048)
			(end -0.67945 0.3048)
			(stroke
				(width 0.1)
				(type default)
			)
			(layer "F.Fab")
		)
		(fp_line
			(start -0.12065 0.2794)
			(end -0.12065 0.3048)
			(stroke
				(width 0.1)
				(type default)
			)
			(layer "F.Fab")
		)
		(fp_line
			(start -0.12065 -0.2794)
			(end 0.12065 -0.2794)
			(stroke
				(width 0.1)
				(type default)
			)
			(layer "F.Fab")
		)
		(fp_line
			(start -0.12065 -0.305054)
			(end -0.12065 -0.2794)
			(stroke
				(width 0.1)
				(type default)
			)
			(layer "F.Fab")
		)
		(fp_line
			(start -0.67945 0.3048)
			(end -0.67945 -0.305054)
			(stroke
				(width 0.1)
				(type default)
			)
			(layer "F.Fab")
		)
		(fp_line
			(start -0.67945 -0.305054)
			(end -0.12065 -0.305054)
			(stroke
				(width 0.1)
				(type default)
			)
			(layer "F.Fab")
		)
		(pad "1" smd circle
			(at -0.40005 0 180)
			(size 0 0)
			(layers "F.Cu" "F.Mask" "F.Paste")
			(net "P3V3_AUX")
		)
		(pad "2" smd circle
			(at 0.40005 0 180)
			(size 0 0)
			(layers "F.Cu" "F.Mask" "F.Paste")
			(net "PU_PCH_VRALERT_N")
		)
	)
)
